(kicad_pcb
	(version 20241229)
	(generator "pcbnew")
	(generator_version "9.0")
	(general
		(thickness 1.6296)
		(legacy_teardrops no)
	)
	(paper "A3")
	(title_block
		(title "Thunderbolt to 10GbE adapter")
		(date "2026-04-21")
		(rev "1.1.0")
		(company "Antmicro Ltd")
		(comment 1 "www.antmicro.com")
		(comment 9 "footprint 288 of 703 (U14), pads 166-244 of 503")
	)
	(layers
		(0 "F.Cu" signal)
		(4 "In1.Cu" signal)
		(6 "In2.Cu" signal)
		(8 "In3.Cu" signal)
		(10 "In4.Cu" signal)
		(12 "In5.Cu" signal)
		(14 "In6.Cu" signal)
		(2 "B.Cu" signal)
		(9 "F.Adhes" user "F.Adhesive")
		(11 "B.Adhes" user "B.Adhesive")
		(13 "F.Paste" user)
		(15 "B.Paste" user)
		(5 "F.SilkS" user "F.Silkscreen")
		(7 "B.SilkS" user "B.Silkscreen")
		(1 "F.Mask" user)
		(3 "B.Mask" user)
		(17 "Dwgs.User" user "User.Drawings")
		(19 "Cmts.User" user "User.Comments")
		(21 "Eco1.User" user "User.Eco1")
		(23 "Eco2.User" user "User.Eco2")
		(25 "Edge.Cuts" user)
		(27 "Margin" user)
		(31 "F.CrtYd" user "F.Courtyard")
		(29 "B.CrtYd" user "B.Courtyard")
		(35 "F.Fab" user)
		(33 "B.Fab" user)
	)
	(footprint "antmicro-footprints:FCBGA-503_22x22mm_Layout21x24_P1mm"
		(layer "F.Cu")
		(at 151.005 81.499999 -90)
		(property "Reference" "U14"
			(at -11.499999 11.005 0)
			(layer "F.SilkS")
			(effects
				(font
					(size 0.7 0.7)
					(thickness 0.15)
				)
				(justify left bottom)
			)
		)
		(property "Value" "EZX710AT2_S_LMR5"
			(at -11.4 12.5 270)
			(layer "F.Fab")
			(effects
				(font
					(size 0.7 0.7)
					(thickness 0.15)
				)
				(justify left bottom)
			)
		)
		(property "Datasheet" "https://www.google.com/url?sa=t&source=web&rct=j&opi=89978449&url=https://cdrdv2-public.intel.com/596333/596333_X710-TM4_Datasheet_v_2_4.pdf&ved=2ahUKEwiSuv20_sCOAxXVCRAIHdxGO_UQFnoECBEQAQ&usg=AOvVaw1CjGyrGWE8ZvOdw4VBsY6U"
			(at 0 0 270)
			(layer "F.Fab")
			(effects
				(font
					(size 0.7 0.7)
					(thickness 0.15)
				)
				(justify left bottom)
			)
		)
		(property "Description" "Ethernet ICs Intel Ethernet Controller 10 Gigabit X7"
			(at 0 0 270)
			(layer "F.Fab")
			(effects
				(font
					(size 0.7 0.7)
					(thickness 0.15)
				)
				(justify left bottom)
			)
		)
		(property "MPN" "EZX710AT2 S LMR5"
			(at 0 0 270)
			(unlocked yes)
			(layer "F.Fab")
			(hide yes)
			(effects
				(font
					(size 1 1)
					(thickness 0.15)
				)
			)
		)
		(property "Manufacturer" "Intel"
			(at 0 0 270)
			(unlocked yes)
			(layer "F.Fab")
			(hide yes)
			(effects
				(font
					(size 1 1)
					(thickness 0.15)
				)
			)
		)
		(property "Author" "Antmicro"
			(at 0 0 270)
			(unlocked yes)
			(layer "F.Fab")
			(hide yes)
			(effects
				(font
					(size 1 1)
					(thickness 0.15)
				)
			)
		)
		(property "License" "Apache-2.0"
			(at 0 0 270)
			(unlocked yes)
			(layer "F.Fab")
			(hide yes)
			(effects
				(font
					(size 1 1)
					(thickness 0.15)
				)
			)
		)
		(sheetname "/X710-AT2 power/")
		(sheetfile "x710-at2-power.kicad_sch")
		(attr smd)
		(pad "D40" smd circle
			(at 9.25 -7.355 270)
			(size 0.5 0.5)
			(layers "F.Cu" "F.Mask" "F.Paste")
			(net 23 "GND")
			(pinfunction "AVSS")
			(pintype "passive")
		)
		(pad "D42" smd circle
			(at 10.25 -7.355 270)
			(size 0.5 0.5)
			(layers "F.Cu" "F.Mask" "F.Paste")
			(net 115 "/X710-AT2 Misc/50MHZ_XTAL.+")
			(pinfunction "XTAL_P")
			(pintype "input")
		)
		(pad "E1" smd circle
			(at -10.25 -6.49 270)
			(size 0.5 0.5)
			(layers "F.Cu" "F.Mask" "F.Paste")
			(net 75 "/X710-AT2 Misc/AUX_PWR")
			(pinfunction "AUX_PWR")
			(pintype "tri_state")
		)
		(pad "E3" smd circle
			(at -9.25 -6.49 270)
			(size 0.5 0.5)
			(layers "F.Cu" "F.Mask" "F.Paste")
			(net 103 "/X710-AT2 Misc/MAIN_PWR_OK")
			(pinfunction "MAIN_PWR_OK")
			(pintype "input")
		)
		(pad "E5" smd circle
			(at -8.25 -6.49 270)
			(size 0.5 0.5)
			(layers "F.Cu" "F.Mask" "F.Paste")
			(net 110 "/X710-AT2 10GbE/~{PHY_RESET_3V3_R}")
			(pinfunction "SDP0_0")
			(pintype "tri_state")
		)
		(pad "E7" smd circle
			(at -7.25 -6.49 270)
			(size 0.5 0.5)
			(layers "F.Cu" "F.Mask" "F.Paste")
			(net 537 "unconnected-(U14C-SDP2_2-PadE7)")
			(pinfunction "SDP2_2")
			(pintype "passive+no_connect")
		)
		(pad "E9" smd circle
			(at -6.25 -6.49 270)
			(size 0.5 0.5)
			(layers "F.Cu" "F.Mask" "F.Paste")
			(net 522 "unconnected-(U14F-SYNCE_LOCK_1-PadE9)")
			(pinfunction "SYNCE_LOCK_1")
			(pintype "output+no_connect")
		)
		(pad "E11" smd circle
			(at -5.25 -6.49 270)
			(size 0.5 0.5)
			(layers "F.Cu" "F.Mask" "F.Paste")
			(net 565 "unconnected-(U14F-SYNCE_LOCK_2-PadE11)")
			(pinfunction "SYNCE_LOCK_2")
			(pintype "output+no_connect")
		)
		(pad "E13" smd circle
			(at -4.25 -6.49 270)
			(size 0.5 0.5)
			(layers "F.Cu" "F.Mask" "F.Paste")
			(net 514 "unconnected-(U14F-SYNCE_CLKOUT_3-PadE13)")
			(pinfunction "SYNCE_CLKOUT_3")
			(pintype "output+no_connect")
		)
		(pad "E15" smd circle
			(at -3.25 -6.49 270)
			(size 0.5 0.5)
			(layers "F.Cu" "F.Mask" "F.Paste")
			(net 106 "/X710-AT2 Misc/PHY_TDI")
			(pinfunction "PHY_TDI")
			(pintype "input")
		)
		(pad "E17" smd circle
			(at -2.25 -6.49 270)
			(size 0.5 0.5)
			(layers "F.Cu" "F.Mask" "F.Paste")
			(net 104 "/X710-AT2 Misc/PHY_TCK")
			(pinfunction "PHY_TCK")
			(pintype "input")
		)
		(pad "E19" smd circle
			(at -1.25 -6.49 270)
			(size 0.5 0.5)
			(layers "F.Cu" "F.Mask" "F.Paste")
			(net 129 "/X710-AT2 RSVD/RSVDE19_1P88V")
			(pinfunction "RSVDE19_1P88V")
			(pintype "passive")
		)
		(pad "E21" smd circle
			(at -0.25 -6.49 270)
			(size 0.5 0.5)
			(layers "F.Cu" "F.Mask" "F.Paste")
			(net 23 "GND")
			(pinfunction "RSVDE21_VSS")
			(pintype "passive")
		)
		(pad "E23" smd circle
			(at 0.75 -6.49 270)
			(size 0.5 0.5)
			(layers "F.Cu" "F.Mask" "F.Paste")
			(net 23 "GND")
			(pinfunction "RSVDE23_VSS")
			(pintype "passive")
		)
		(pad "E25" smd circle
			(at 1.75 -6.49 270)
			(size 0.5 0.5)
			(layers "F.Cu" "F.Mask" "F.Paste")
			(net 23 "GND")
			(pinfunction "RSVDE25_VSS")
			(pintype "passive")
		)
		(pad "E27" smd circle
			(at 2.75 -6.49 270)
			(size 0.5 0.5)
			(layers "F.Cu" "F.Mask" "F.Paste")
			(net 10 "AVDDH")
			(pinfunction "P1_AVDDH")
			(pintype "power_in")
		)
		(pad "E29" smd circle
			(at 3.75 -6.49 270)
			(size 0.5 0.5)
			(layers "F.Cu" "F.Mask" "F.Paste")
			(net 10 "AVDDH")
			(pinfunction "P1_AVDDH")
			(pintype "passive")
		)
		(pad "E31" smd circle
			(at 4.75 -6.49 270)
			(size 0.5 0.5)
			(layers "F.Cu" "F.Mask" "F.Paste")
			(net 23 "GND")
			(pinfunction "AVSS")
			(pintype "passive")
		)
		(pad "E33" smd circle
			(at 5.75 -6.49 270)
			(size 0.5 0.5)
			(layers "F.Cu" "F.Mask" "F.Paste")
			(net 23 "GND")
			(pinfunction "AVSS")
			(pintype "passive")
		)
		(pad "E35" smd circle
			(at 6.75 -6.49 270)
			(size 0.5 0.5)
			(layers "F.Cu" "F.Mask" "F.Paste")
			(net 10 "AVDDH")
			(pinfunction "P0_AVDDH")
			(pintype "power_in")
		)
		(pad "E37" smd circle
			(at 7.75 -6.49 270)
			(size 0.5 0.5)
			(layers "F.Cu" "F.Mask" "F.Paste")
			(net 10 "AVDDH")
			(pinfunction "P0_AVDDH")
			(pintype "passive")
		)
		(pad "E39" smd circle
			(at 8.75 -6.49 270)
			(size 0.5 0.5)
			(layers "F.Cu" "F.Mask" "F.Paste")
			(net 63 "/X710-AT2 10GbE/BIAS_RDAC")
			(pinfunction "BIAS_RDAC")
			(pintype "passive")
		)
		(pad "E41" smd circle
			(at 9.75 -6.49 270)
			(size 0.5 0.5)
			(layers "F.Cu" "F.Mask" "F.Paste")
			(net 120 "/X710-AT2 Misc/50MHZ_XTAL.-")
			(pinfunction "XTAL_N")
			(pintype "input")
		)
		(pad "F2" smd circle
			(at -9.75 -5.625 270)
			(size 0.5 0.5)
			(layers "F.Cu" "F.Mask" "F.Paste")
			(net 140 "/X710-AT2 Misc/NCSI.TXD_0")
			(pinfunction "NCSI_TXD_0")
			(pintype "input")
		)
		(pad "F4" smd circle
			(at -8.75 -5.625 270)
			(size 0.5 0.5)
			(layers "F.Cu" "F.Mask" "F.Paste")
			(net 440 "Net-(U14D-NCSI_ARB_OUT)")
			(pinfunction "NCSI_ARB_OUT")
			(pintype "output")
		)
		(pad "F6" smd circle
			(at -7.75 -5.625 270)
			(size 0.5 0.5)
			(layers "F.Cu" "F.Mask" "F.Paste")
			(net 583 "unconnected-(U14C-SDP2_0-PadF6)")
			(pinfunction "SDP2_0")
			(pintype "passive+no_connect")
		)
		(pad "F8" smd circle
			(at -6.75 -5.625 270)
			(size 0.5 0.5)
			(layers "F.Cu" "F.Mask" "F.Paste")
			(net 531 "unconnected-(U14F-SYNCE_LOCK_0-PadF8)")
			(pinfunction "SYNCE_LOCK_0")
			(pintype "output+no_connect")
		)
		(pad "F10" smd circle
			(at -5.75 -5.625 270)
			(size 0.5 0.5)
			(layers "F.Cu" "F.Mask" "F.Paste")
			(net 543 "unconnected-(U14F-SYNCE_CLKOUT_1-PadF10)")
			(pinfunction "SYNCE_CLKOUT_1")
			(pintype "output+no_connect")
		)
		(pad "F12" smd circle
			(at -4.75 -5.625 270)
			(size 0.5 0.5)
			(layers "F.Cu" "F.Mask" "F.Paste")
			(net 569 "unconnected-(U14F-SYNCE_LOCK_3-PadF12)")
			(pinfunction "SYNCE_LOCK_3")
			(pintype "output+no_connect")
		)
		(pad "F14" smd circle
			(at -3.75 -5.625 270)
			(size 0.5 0.5)
			(layers "F.Cu" "F.Mask" "F.Paste")
			(net 124 "/X710-AT2 10GbE/~{P1_INT}")
			(pinfunction "P1_INT_MLC")
			(pintype "passive")
		)
		(pad "F16" smd circle
			(at -2.75 -5.625 270)
			(size 0.5 0.5)
			(layers "F.Cu" "F.Mask" "F.Paste")
			(net 107 "/X710-AT2 Misc/PHY_TDO")
			(pinfunction "PHY_TDO")
			(pintype "open_collector")
		)
		(pad "F18" smd circle
			(at -1.75 -5.625 270)
			(size 0.5 0.5)
			(layers "F.Cu" "F.Mask" "F.Paste")
			(net 23 "GND")
			(pinfunction "RSVDF18_VSS")
			(pintype "passive")
		)
		(pad "F20" smd circle
			(at -0.75 -5.625 270)
			(size 0.5 0.5)
			(layers "F.Cu" "F.Mask" "F.Paste")
			(net 23 "GND")
			(pinfunction "RSVDF20_VSS")
			(pintype "passive")
		)
		(pad "F22" smd circle
			(at 0.25 -5.625 270)
			(size 0.5 0.5)
			(layers "F.Cu" "F.Mask" "F.Paste")
			(net 23 "GND")
			(pinfunction "RSVDF22_VSS")
			(pintype "passive")
		)
		(pad "F24" smd circle
			(at 1.25 -5.625 270)
			(size 0.5 0.5)
			(layers "F.Cu" "F.Mask" "F.Paste")
			(net 23 "GND")
			(pinfunction "VSS")
			(pintype "power_in")
		)
		(pad "F26" smd circle
			(at 2.25 -5.625 270)
			(size 0.5 0.5)
			(layers "F.Cu" "F.Mask" "F.Paste")
			(net 23 "GND")
			(pinfunction "VSS")
			(pintype "passive")
		)
		(pad "F28" smd circle
			(at 3.25 -5.625 270)
			(size 0.5 0.5)
			(layers "F.Cu" "F.Mask" "F.Paste")
			(net 23 "GND")
			(pinfunction "VSS")
			(pintype "passive")
		)
		(pad "F30" smd circle
			(at 4.25 -5.625 270)
			(size 0.5 0.5)
			(layers "F.Cu" "F.Mask" "F.Paste")
			(net 23 "GND")
			(pinfunction "VSS")
			(pintype "passive")
		)
		(pad "F32" smd circle
			(at 5.25 -5.625 270)
			(size 0.5 0.5)
			(layers "F.Cu" "F.Mask" "F.Paste")
			(net 23 "GND")
			(pinfunction "VSS")
			(pintype "passive")
		)
		(pad "F34" smd circle
			(at 6.25 -5.625 270)
			(size 0.5 0.5)
			(layers "F.Cu" "F.Mask" "F.Paste")
			(net 23 "GND")
			(pinfunction "VSS")
			(pintype "passive")
		)
		(pad "F36" smd circle
			(at 7.25 -5.625 270)
			(size 0.5 0.5)
			(layers "F.Cu" "F.Mask" "F.Paste")
			(net 23 "GND")
			(pinfunction "VSS")
			(pintype "passive")
		)
		(pad "F38" smd circle
			(at 8.25 -5.625 270)
			(size 0.5 0.5)
			(layers "F.Cu" "F.Mask" "F.Paste")
			(net 23 "GND")
			(pinfunction "RSVDF38_VSS")
			(pintype "passive")
		)
		(pad "F40" smd circle
			(at 9.25 -5.625 270)
			(size 0.5 0.5)
			(layers "F.Cu" "F.Mask" "F.Paste")
			(net 23 "GND")
			(pinfunction "AVSS")
			(pintype "passive")
		)
		(pad "F42" smd circle
			(at 10.25 -5.625 270)
			(size 0.5 0.5)
			(layers "F.Cu" "F.Mask" "F.Paste")
			(net 23 "GND")
			(pinfunction "AVSS")
			(pintype "passive")
		)
		(pad "G1" smd circle
			(at -10.25 -4.76 270)
			(size 0.5 0.5)
			(layers "F.Cu" "F.Mask" "F.Paste")
			(net 138 "/X710-AT2 Misc/NCSI.TXD_1")
			(pinfunction "NCSI_TXD_1")
			(pintype "input")
		)
		(pad "G3" smd circle
			(at -9.25 -4.76 270)
			(size 0.5 0.5)
			(layers "F.Cu" "F.Mask" "F.Paste")
			(net 145 "/X710-AT2 Misc/NCSI.ARB_IN")
			(pinfunction "NCSI_ARB_IN")
			(pintype "input")
		)
		(pad "G5" smd circle
			(at -8.25 -4.76 270)
			(size 0.5 0.5)
			(layers "F.Cu" "F.Mask" "F.Paste")
			(net 121 "/X710-AT2 10GbE/~{P0_INT_R}")
			(pinfunction "SDP0_1")
			(pintype "tri_state")
		)
		(pad "G7" smd circle
			(at -7.25 -4.76 270)
			(size 0.5 0.5)
			(layers "F.Cu" "F.Mask" "F.Paste")
			(net 550 "unconnected-(U14C-SDP2_3-PadG7)")
			(pinfunction "SDP2_3")
			(pintype "passive+no_connect")
		)
		(pad "G9" smd circle
			(at -6.25 -4.76 270)
			(size 0.5 0.5)
			(layers "F.Cu" "F.Mask" "F.Paste")
			(net 555 "unconnected-(U14F-SYNCE_CLKOUT_0-PadG9)")
			(pinfunction "SYNCE_CLKOUT_0")
			(pintype "output+no_connect")
		)
		(pad "G11" smd circle
			(at -5.25 -4.76 270)
			(size 0.5 0.5)
			(layers "F.Cu" "F.Mask" "F.Paste")
			(net 567 "unconnected-(U14F-SYNCE_CLKOUT_2-PadG11)")
			(pinfunction "SYNCE_CLKOUT_2")
			(pintype "output+no_connect")
		)
		(pad "G13" smd circle
			(at -4.25 -4.76 270)
			(size 0.5 0.5)
			(layers "F.Cu" "F.Mask" "F.Paste")
			(net 575 "unconnected-(U14F-RSVDG13_NC-PadG13)")
			(pinfunction "RSVDG13_NC")
			(pintype "passive+no_connect")
		)
		(pad "G15" smd circle
			(at -3.25 -4.76 270)
			(size 0.5 0.5)
			(layers "F.Cu" "F.Mask" "F.Paste")
			(net 541 "unconnected-(U14F-RSVDG15_NC-PadG15)")
			(pinfunction "RSVDG15_NC")
			(pintype "passive+no_connect")
		)
		(pad "G17" smd circle
			(at -2.25 -4.76 270)
			(size 0.5 0.5)
			(layers "F.Cu" "F.Mask" "F.Paste")
			(net 131 "/X710-AT2 10GbE/TPIN_5")
			(pinfunction "TPIN_5")
			(pintype "passive")
		)
		(pad "G19" smd circle
			(at -1.25 -4.76 270)
			(size 0.5 0.5)
			(layers "F.Cu" "F.Mask" "F.Paste")
			(net 23 "GND")
			(pinfunction "RSVDG19_VSS")
			(pintype "passive")
		)
		(pad "G21" smd circle
			(at -0.25 -4.76 270)
			(size 0.5 0.5)
			(layers "F.Cu" "F.Mask" "F.Paste")
			(net 23 "GND")
			(pinfunction "RSVDG21_VSS")
			(pintype "passive")
		)
		(pad "G23" smd circle
			(at 0.75 -4.76 270)
			(size 0.5 0.5)
			(layers "F.Cu" "F.Mask" "F.Paste")
			(net 23 "GND")
			(pinfunction "RSVDG23_VSS")
			(pintype "passive")
		)
		(pad "G25" smd circle
			(at 1.75 -4.76 270)
			(size 0.5 0.5)
			(layers "F.Cu" "F.Mask" "F.Paste")
			(net 18 "+1V88")
			(pinfunction "VDDIO1")
			(pintype "power_in")
		)
		(pad "G27" smd circle
			(at 2.75 -4.76 270)
			(size 0.5 0.5)
			(layers "F.Cu" "F.Mask" "F.Paste")
			(net 6 "DVDD")
			(pinfunction "DVDD")
			(pintype "power_in")
		)
		(pad "G29" smd circle
			(at 3.75 -4.76 270)
			(size 0.5 0.5)
			(layers "F.Cu" "F.Mask" "F.Paste")
			(net 6 "DVDD")
			(pinfunction "DVDD")
			(pintype "passive")
		)
		(pad "G31" smd circle
			(at 4.75 -4.76 270)
			(size 0.5 0.5)
			(layers "F.Cu" "F.Mask" "F.Paste")
			(net 6 "DVDD")
			(pinfunction "DVDD")
			(pintype "passive")
		)
		(pad "G33" smd circle
			(at 5.75 -4.76 270)
			(size 0.5 0.5)
			(layers "F.Cu" "F.Mask" "F.Paste")
			(net 6 "DVDD")
			(pinfunction "DVDD")
			(pintype "passive")
		)
		(pad "G35" smd circle
			(at 6.75 -4.76 270)
			(size 0.5 0.5)
			(layers "F.Cu" "F.Mask" "F.Paste")
			(net 6 "DVDD")
			(pinfunction "DVDD")
			(pintype "passive")
		)
		(pad "G37" smd circle
			(at 7.75 -4.76 270)
			(size 0.5 0.5)
			(layers "F.Cu" "F.Mask" "F.Paste")
			(net 18 "+1V88")
			(pinfunction "VDDIO1")
			(pintype "passive")
		)
		(pad "G39" smd circle
			(at 8.75 -4.76 270)
			(size 0.5 0.5)
			(layers "F.Cu" "F.Mask" "F.Paste")
			(net 22 "PLL_VDD")
			(pinfunction "PLL_VDD")
			(pintype "power_in")
		)
		(pad "G41" smd circle
			(at 9.75 -4.76 270)
			(size 0.5 0.5)
			(layers "F.Cu" "F.Mask" "F.Paste")
			(net 23 "GND")
			(pinfunction "AVSS")
			(pintype "passive")
		)
		(pad "H2" smd circle
			(at -9.75 -3.895 270)
			(size 0.5 0.5)
			(layers "F.Cu" "F.Mask" "F.Paste")
			(net 144 "/X710-AT2 Misc/NCSI.REF_CLK")
			(pinfunction "NCSI_CLK_IN")
			(pintype "input")
		)
		(pad "H4" smd circle
			(at -8.75 -3.895 270)
			(size 0.5 0.5)
			(layers "F.Cu" "F.Mask" "F.Paste")
			(net 143 "/X710-AT2 Misc/NCSI.TX_EN")
			(pinfunction "NCSI_TX_EN")
			(pintype "input")
		)
		(pad "H6" smd circle
			(at -7.75 -3.895 270)
			(size 0.5 0.5)
			(layers "F.Cu" "F.Mask" "F.Paste")
			(net 486 "unconnected-(U14C-SDP1_3-PadH6)")
			(pinfunction "SDP1_3")
			(pintype "passive+no_connect")
		)
		(pad "H8" smd circle
			(at -6.75 -3.895 270)
			(size 0.5 0.5)
			(layers "F.Cu" "F.Mask" "F.Paste")
			(net 551 "unconnected-(U14D-GPIO_4-PadH8)")
			(pinfunction "GPIO_4")
			(pintype "passive+no_connect")
		)
		(pad "H10" smd circle
			(at -5.75 -3.895 270)
			(size 0.5 0.5)
			(layers "F.Cu" "F.Mask" "F.Paste")
			(net 558 "unconnected-(U14F-P1_PTP_SYNC0-PadH10)")
			(pinfunction "P1_PTP_SYNC0")
			(pintype "passive+no_connect")
		)
		(pad "H12" smd circle
			(at -4.75 -3.895 270)
			(size 0.5 0.5)
			(layers "F.Cu" "F.Mask" "F.Paste")
			(net 561 "unconnected-(U14F-P1_PTP_SYNC1-PadH12)")
			(pinfunction "P1_PTP_SYNC1")
			(pintype "passive+no_connect")
		)
		(pad "H14" smd circle
			(at -3.75 -3.895 270)
			(size 0.5 0.5)
			(layers "F.Cu" "F.Mask" "F.Paste")
			(net 459 "unconnected-(U14F-RSVDH14_NC-PadH14)")
			(pinfunction "RSVDH14_NC")
			(pintype "passive+no_connect")
		)
		(pad "H16" smd circle
			(at -2.75 -3.895 270)
			(size 0.5 0.5)
			(layers "F.Cu" "F.Mask" "F.Paste")
			(net 586 "unconnected-(U14F-RSVDH16_NC-PadH16)")
			(pinfunction "RSVDH16_NC")
			(pintype "passive+no_connect")
		)
		(pad "H18" smd circle
			(at -1.75 -3.895 270)
			(size 0.5 0.5)
			(layers "F.Cu" "F.Mask" "F.Paste")
			(net 23 "GND")
			(pinfunction "RSVH18_VSS")
			(pintype "passive")
		)
		(pad "H20" smd circle
			(at -0.75 -3.895 270)
			(size 0.5 0.5)
			(layers "F.Cu" "F.Mask" "F.Paste")
			(net 130 "/X710-AT2 10GbE/TPIN_3")
			(pinfunction "TPIN_3")
			(pintype "passive")
		)
		(pad "H22" smd circle
			(at 0.25 -3.895 270)
			(size 0.5 0.5)
			(layers "F.Cu" "F.Mask" "F.Paste")
			(net 23 "GND")
			(pinfunction "RSVDH22_VSS")
			(pintype "passive")
		)
		(pad "H24" smd circle
			(at 1.25 -3.895 270)
			(size 0.5 0.5)
			(layers "F.Cu" "F.Mask" "F.Paste")
			(net 23 "GND")
			(pinfunction "RSVDH24_VSS")
			(pintype "passive")
		)
		(pad "H26" smd circle
			(at 2.25 -3.895 270)
			(size 0.5 0.5)
			(layers "F.Cu" "F.Mask" "F.Paste")
			(net 23 "GND")
			(pinfunction "VSSA")
			(pintype "passive")
		)
		(pad "H28" smd circle
			(at 3.25 -3.895 270)
			(size 0.5 0.5)
			(layers "F.Cu" "F.Mask" "F.Paste")
			(net 23 "GND")
			(pinfunction "VSSA")
			(pintype "passive")
		)
	)
)
